# S9S_MB_2U (Grand Teton) — schematic netlist excerpt (pin names and nets, part order shuffled) for the footprints in the layout excerpt that follows; sources: Cadence DE-HDL packaged netlist, KiCad conversion of 03242023_DA0F0TMBIJ0_F0T_Motherboard_J_brd_V01_OCP.brd

PC1201_P1_3  Q_CAP  22UF 16V 20% X6S  pkg C0805  page 290 : A = SW_P12V_PVCCFA_EHV_FIVRA_CPU1_R ; B = GND
R4766  Q_RES  49.9 1% CHIP  pkg 0402LF  page 183 : A = E1S_0_CLK_OE_N ; B = E1S_0_CLKREQ_N
PR176  Q_RES  1 1% CHIP  pkg 0402LF  page 266 : A = PVCCIN_CPU0_VCC ; B = P3V3_AUX

(kicad_pcb
	(version 20260206)
	(generator "pcbnew")
	(generator_version "10.0")
	(general
		(thickness 1.6)
		(legacy_teardrops no)
	)
	(paper "A4")
	(title_block
		(title "03242023_DA0F0TMBIJ0_F0T_Motherboard_J_brd_V01_OCP.brd")
		(comment 1 "Grand Teton / footprints 5262-5264 of 6105")
	)
	(layers
		(0 "F.Cu" signal "TOP")
		(4 "In1.Cu" signal "GND")
		(6 "In2.Cu" signal "IN1")
		(8 "In3.Cu" signal "GND1")
		(10 "In4.Cu" signal "IN2")
		(12 "In5.Cu" signal "GND2")
		(14 "In6.Cu" signal "IN3")
		(16 "In7.Cu" signal "GND3")
		(18 "In8.Cu" signal "VCC")
		(20 "In9.Cu" signal "VCC1")
		(22 "In10.Cu" signal "GND4")
		(24 "In11.Cu" signal "IN4")
		(26 "In12.Cu" signal "GND5")
		(28 "In13.Cu" signal "IN5")
		(30 "In14.Cu" signal "GND6")
		(32 "In15.Cu" signal "IN6")
		(34 "In16.Cu" signal "GND7")
		(2 "B.Cu" signal "BOTTOM")
		(9 "F.Adhes" user "F.Adhesive")
		(11 "B.Adhes" user "B.Adhesive")
		(13 "F.Paste" user "Package Geometry/Pastemask Top")
		(15 "B.Paste" user "Package Geometry/Pastemask Bottom")
		(5 "F.SilkS" user "Ref Des/Silkscreen Top")
		(7 "B.SilkS" user "Ref Des/Silkscreen Bottom")
		(1 "F.Mask" user "Board Geometry/Soldermask Top")
		(3 "B.Mask" user "Board Geometry/Soldermask Bottom")
		(17 "Dwgs.User" user "User.Drawings")
		(19 "Cmts.User" user "User.Comments")
		(21 "Eco1.User" user "User.Eco1")
		(23 "Eco2.User" user "User.Eco2")
		(25 "Edge.Cuts" user "Board Geometry/Outline")
		(27 "Margin" user)
		(31 "F.CrtYd" user "Package Geometry/Place Bound Top")
		(29 "B.CrtYd" user "Package Geometry/Place Bound Bottom")
		(35 "F.Fab" user "Ref Des/Assembly Top")
		(33 "B.Fab" user "Ref Des/Assembly Bottom")
	)
	(footprint ""
		(layer "B.Cu")
		(at 361.691174 -362.698792 180)
		(property "Reference" "PR176"
			(at 0 0 0)
			(layer "B.SilkS")
			(hide yes)
			(effects
				(font
					(size 1.27 1.27)
				)
				(justify mirror)
			)
		)
		(property "Value" ""
			(at 0 0 0)
			(layer "B.Fab")
			(effects
				(font
					(size 1.27 1.27)
				)
				(justify mirror)
			)
		)
		(duplicate_pad_numbers_are_jumpers no)
		(fp_line
			(start 0.7874 0.4064)
			(end 0.7874 -0.4064)
			(stroke
				(width 0.1524)
				(type default)
			)
			(layer "B.SilkS")
		)
		(fp_line
			(start 0.7874 -0.4064)
			(end -0.7874 -0.4064)
			(stroke
				(width 0.1524)
				(type default)
			)
			(layer "B.SilkS")
		)
		(fp_line
			(start -0.7874 0.4064)
			(end 0.7874 0.4064)
			(stroke
				(width 0.1524)
				(type default)
			)
			(layer "B.SilkS")
		)
		(fp_line
			(start -0.7874 -0.4064)
			(end -0.7874 0.4064)
			(stroke
				(width 0.1524)
				(type default)
			)
			(layer "B.SilkS")
		)
		(fp_line
			(start 0.67945 0.3048)
			(end 0.67945 -0.305054)
			(stroke
				(width 0.1)
				(type default)
			)
			(layer "B.Fab")
		)
		(fp_line
			(start 0.67945 -0.305054)
			(end 0.12065 -0.305054)
			(stroke
				(width 0.1)
				(type default)
			)
			(layer "B.Fab")
		)
		(fp_line
			(start 0.12065 0.3048)
			(end 0.67945 0.3048)
			(stroke
				(width 0.1)
				(type default)
			)
			(layer "B.Fab")
		)
		(fp_line
			(start 0.12065 0.2794)
			(end 0.12065 0.3048)
			(stroke
				(width 0.1)
				(type default)
			)
			(layer "B.Fab")
		)
		(fp_line
			(start 0.12065 -0.2794)
			(end -0.12065 -0.2794)
			(stroke
				(width 0.1)
				(type default)
			)
			(layer "B.Fab")
		)
		(fp_line
			(start 0.12065 -0.305054)
			(end 0.12065 -0.2794)
			(stroke
				(width 0.1)
				(type default)
			)
			(layer "B.Fab")
		)
		(fp_line
			(start -0.120396 0.3048)
			(end -0.120396 0.2794)
			(stroke
				(width 0.1)
				(type default)
			)
			(layer "B.Fab")
		)
		(fp_line
			(start -0.120396 0.2794)
			(end 0.12065 0.2794)
			(stroke
				(width 0.1)
				(type default)
			)
			(layer "B.Fab")
		)
		(fp_line
			(start -0.12065 -0.2794)
			(end -0.12065 -0.3048)
			(stroke
				(width 0.1)
				(type default)
			)
			(layer "B.Fab")
		)
		(fp_line
			(start -0.12065 -0.3048)
			(end -0.67945 -0.3048)
			(stroke
				(width 0.1)
				(type default)
			)
			(layer "B.Fab")
		)
		(fp_line
			(start -0.67945 0.3048)
			(end -0.120396 0.3048)
			(stroke
				(width 0.1)
				(type default)
			)
			(layer "B.Fab")
		)
		(fp_line
			(start -0.67945 -0.3048)
			(end -0.67945 0.3048)
			(stroke
				(width 0.1)
				(type default)
			)
			(layer "B.Fab")
		)
		(pad "1" smd circle
			(at 0.40005 0)
			(size 0 0)
			(layers "B.Cu" "B.Mask" "B.Paste")
			(net "PVCCIN_CPU0_VCC")
		)
		(pad "2" smd circle
			(at -0.40005 0)
			(size 0 0)
			(layers "B.Cu" "B.Mask" "B.Paste")
			(net "P3V3_AUX")
		)
	)
	(footprint ""
		(layer "B.Cu")
		(at 309.55742 -33.22574 180)
		(property "Reference" "R4766"
			(at 0 0 0)
			(layer "B.SilkS")
			(hide yes)
			(effects
				(font
					(size 1.27 1.27)
				)
				(justify mirror)
			)
		)
		(property "Value" ""
			(at 0 0 0)
			(layer "B.Fab")
			(effects
				(font
					(size 1.27 1.27)
				)
				(justify mirror)
			)
		)
		(duplicate_pad_numbers_are_jumpers no)
		(fp_line
			(start 0.7874 0.4064)
			(end 0.7874 -0.4064)
			(stroke
				(width 0.1524)
				(type default)
			)
			(layer "B.SilkS")
		)
		(fp_line
			(start 0.7874 -0.4064)
			(end -0.7874 -0.4064)
			(stroke
				(width 0.1524)
				(type default)
			)
			(layer "B.SilkS")
		)
		(fp_line
			(start -0.7874 0.4064)
			(end 0.7874 0.4064)
			(stroke
				(width 0.1524)
				(type default)
			)
			(layer "B.SilkS")
		)
		(fp_line
			(start -0.7874 -0.4064)
			(end -0.7874 0.4064)
			(stroke
				(width 0.1524)
				(type default)
			)
			(layer "B.SilkS")
		)
		(fp_line
			(start 0.67945 0.3048)
			(end 0.67945 -0.305054)
			(stroke
				(width 0.1)
				(type default)
			)
			(layer "B.Fab")
		)
		(fp_line
			(start 0.67945 -0.305054)
			(end 0.12065 -0.305054)
			(stroke
				(width 0.1)
				(type default)
			)
			(layer "B.Fab")
		)
		(fp_line
			(start 0.12065 0.3048)
			(end 0.67945 0.3048)
			(stroke
				(width 0.1)
				(type default)
			)
			(layer "B.Fab")
		)
		(fp_line
			(start 0.12065 0.2794)
			(end 0.12065 0.3048)
			(stroke
				(width 0.1)
				(type default)
			)
			(layer "B.Fab")
		)
		(fp_line
			(start 0.12065 -0.2794)
			(end -0.12065 -0.2794)
			(stroke
				(width 0.1)
				(type default)
			)
			(layer "B.Fab")
		)
		(fp_line
			(start 0.12065 -0.305054)
			(end 0.12065 -0.2794)
			(stroke
				(width 0.1)
				(type default)
			)
			(layer "B.Fab")
		)
		(fp_line
			(start -0.120396 0.3048)
			(end -0.120396 0.2794)
			(stroke
				(width 0.1)
				(type default)
			)
			(layer "B.Fab")
		)
		(fp_line
			(start -0.120396 0.2794)
			(end 0.12065 0.2794)
			(stroke
				(width 0.1)
				(type default)
			)
			(layer "B.Fab")
		)
		(fp_line
			(start -0.12065 -0.2794)
			(end -0.12065 -0.3048)
			(stroke
				(width 0.1)
				(type default)
			)
			(layer "B.Fab")
		)
		(fp_line
			(start -0.12065 -0.3048)
			(end -0.67945 -0.3048)
			(stroke
				(width 0.1)
				(type default)
			)
			(layer "B.Fab")
		)
		(fp_line
			(start -0.67945 0.3048)
			(end -0.120396 0.3048)
			(stroke
				(width 0.1)
				(type default)
			)
			(layer "B.Fab")
		)
		(fp_line
			(start -0.67945 -0.3048)
			(end -0.67945 0.3048)
			(stroke
				(width 0.1)
				(type default)
			)
			(layer "B.Fab")
		)
		(pad "1" smd circle
			(at 0.40005 0)
			(size 0 0)
			(layers "B.Cu" "B.Mask" "B.Paste")
			(net "E1S_0_CLK_OE_N")
		)
		(pad "2" smd circle
			(at -0.40005 0)
			(size 0 0)
			(layers "B.Cu" "B.Mask" "B.Paste")
			(net "E1S_0_CLKREQ_N")
		)
	)
	(footprint ""
		(layer "B.Cu")
		(at 184.969404 -353.573842 90)
		(property "Reference" "PC1201_P1_3"
			(at 0 0 90)
			(layer "B.SilkS")
			(hide yes)
			(effects
				(font
					(size 1.27 1.27)
				)
				(justify mirror)
			)
		)
		(property "Value" ""
			(at 0 0 90)
			(layer "B.Fab")
			(effects
				(font
					(size 1.27 1.27)
				)
				(justify mirror)
			)
		)
		(duplicate_pad_numbers_are_jumpers no)
		(fp_line
			(start 1.524 -0.762)
			(end -1.524 -0.762)
			(stroke
				(width 0.1524)
				(type default)
			)
			(layer "B.SilkS")
		)
		(fp_line
			(start -1.524 -0.762)
			(end -1.524 0.762)
			(stroke
				(width 0.1524)
				(type default)
			)
			(layer "B.SilkS")
		)
		(fp_line
			(start 1.524 0.762)
			(end 1.524 -0.762)
			(stroke
				(width 0.1524)
				(type default)
			)
			(layer "B.SilkS")
		)
		(fp_line
			(start -1.524 0.762)
			(end 1.524 0.762)
			(stroke
				(width 0.1524)
				(type default)
			)
			(layer "B.SilkS")
		)
		(fp_line
			(start 1.1049 -0.724916)
			(end 1.1049 0.724916)
			(stroke
				(width 0.1)
				(type default)
			)
			(layer "B.Fab")
		)
		(fp_line
			(start -1.1049 -0.724916)
			(end 1.1049 -0.724916)
			(stroke
				(width 0.1)
				(type default)
			)
			(layer "B.Fab")
		)
		(fp_line
			(start 1.1049 0.724916)
			(end -1.1049 0.724916)
			(stroke
				(width 0.1)
				(type default)
			)
			(layer "B.Fab")
		)
		(fp_line
			(start -1.1049 0.724916)
			(end -1.1049 -0.724916)
			(stroke
				(width 0.1)
				(type default)
			)
			(layer "B.Fab")
		)
		(pad "1" smd rect
			(at 0.889 0 90)
			(size 1.016 1.27)
			(layers "B.Cu" "B.Mask" "B.Paste")
			(net "SW_P12V_PVCCFA_EHV_FIVRA_CPU1_R")
		)
		(pad "2" smd rect
			(at -0.889 0 90)
			(size 1.016 1.27)
			(layers "B.Cu" "B.Mask" "B.Paste")
			(net "GND")
		)
	)
)
